(kicad_pcb
	(version 20260206)
	(generator "pcbnew")
	(generator_version "10.0")
	(general
		(thickness 1.6)
		(legacy_teardrops no)
	)
	(paper "A4")
	(title_block
		(title "01162023_DA0F0TEBIF0_F0T_Expander_BD_F_brd_V02_OCP.brd")
		(comment 1 "Grand Teton / footprints 3378-3384 of 9728")
	)
	(layers
		(0 "F.Cu" signal "TOP")
		(4 "In1.Cu" signal "GND")
		(6 "In2.Cu" signal "VCC")
		(8 "In3.Cu" signal "VCC1")
		(10 "In4.Cu" signal "GND1")
		(12 "In5.Cu" signal "IN1")
		(14 "In6.Cu" signal "GND2")
		(16 "In7.Cu" signal "IN2")
		(18 "In8.Cu" signal "GND3")
		(20 "In9.Cu" signal "IN3")
		(22 "In10.Cu" signal "GND4")
		(24 "In11.Cu" signal "IN4")
		(26 "In12.Cu" signal "GND5")
		(28 "In13.Cu" signal "IN5")
		(30 "In14.Cu" signal "GND6")
		(32 "In15.Cu" signal "IN6")
		(34 "In16.Cu" signal "GND7")
		(2 "B.Cu" signal "BOTTOM")
		(9 "F.Adhes" user "F.Adhesive")
		(11 "B.Adhes" user "B.Adhesive")
		(13 "F.Paste" user "Package Geometry/Pastemask Top")
		(15 "B.Paste" user "Package Geometry/Pastemask Bottom")
		(5 "F.SilkS" user "Ref Des/Silkscreen Top")
		(7 "B.SilkS" user "Ref Des/Silkscreen Bottom")
		(1 "F.Mask" user "Board Geometry/Soldermask Top")
		(3 "B.Mask" user "Board Geometry/Soldermask Bottom")
		(17 "Dwgs.User" user "User.Drawings")
		(19 "Cmts.User" user "User.Comments")
		(21 "Eco1.User" user "User.Eco1")
		(23 "Eco2.User" user "User.Eco2")
		(25 "Edge.Cuts" user "Board Geometry/Outline")
		(27 "Margin" user)
		(31 "F.CrtYd" user "Package Geometry/Place Bound Top")
		(29 "B.CrtYd" user "Package Geometry/Place Bound Bottom")
		(35 "F.Fab" user "Ref Des/Assembly Top")
		(33 "B.Fab" user "Ref Des/Assembly Bottom")
	)
	(footprint ""
		(layer "F.Cu")
		(at 46.434502 -33.631886 180)
		(property "Reference" "C74"
			(at 0 0 180)
			(layer "F.SilkS")
			(hide yes)
			(effects
				(font
					(size 1.27 1.27)
				)
			)
		)
		(property "Value" ""
			(at 0 0 180)
			(layer "F.Fab")
			(effects
				(font
					(size 1.27 1.27)
				)
			)
		)
		(duplicate_pad_numbers_are_jumpers no)
		(fp_line
			(start 0.299974 0.150114)
			(end -0.299974 0.150114)
			(stroke
				(width 0.1)
				(type default)
			)
			(layer "F.Fab")
		)
		(fp_line
			(start 0.299974 -0.150114)
			(end 0.299974 0.150114)
			(stroke
				(width 0.1)
				(type default)
			)
			(layer "F.Fab")
		)
		(fp_line
			(start -0.299974 0.150114)
			(end -0.299974 -0.150114)
			(stroke
				(width 0.1)
				(type default)
			)
			(layer "F.Fab")
		)
		(fp_line
			(start -0.299974 -0.150114)
			(end 0.299974 -0.150114)
			(stroke
				(width 0.1)
				(type default)
			)
			(layer "F.Fab")
		)
		(pad "1" smd rect
			(at -0.2667 0 180)
			(size 0.3048 0.381)
			(layers "F.Cu" "F.Mask" "F.Paste")
			(net "P5E_PEX0_STN2_TX_DN<43>")
		)
		(pad "2" smd rect
			(at 0.2667 0 180)
			(size 0.3048 0.381)
			(layers "F.Cu" "F.Mask" "F.Paste")
			(net "P5E_PEX0_STN2_TX_C_DN<43>")
		)
	)
	(footprint ""
		(layer "F.Cu")
		(at 187.571634 -25.342342 -90)
		(property "Reference" "R427"
			(at 0 0 270)
			(layer "F.SilkS")
			(hide yes)
			(effects
				(font
					(size 1.27 1.27)
				)
			)
		)
		(property "Value" ""
			(at 0 0 270)
			(layer "F.Fab")
			(effects
				(font
					(size 1.27 1.27)
				)
			)
		)
		(duplicate_pad_numbers_are_jumpers no)
		(fp_line
			(start -0.7874 0.4064)
			(end -0.7874 -0.4064)
			(stroke
				(width 0.1524)
				(type default)
			)
			(layer "F.SilkS")
		)
		(fp_line
			(start 0.7874 0.4064)
			(end -0.7874 0.4064)
			(stroke
				(width 0.1524)
				(type default)
			)
			(layer "F.SilkS")
		)
		(fp_line
			(start -0.7874 -0.4064)
			(end 0.7874 -0.4064)
			(stroke
				(width 0.1524)
				(type default)
			)
			(layer "F.SilkS")
		)
		(fp_line
			(start 0.7874 -0.4064)
			(end 0.7874 0.4064)
			(stroke
				(width 0.1524)
				(type default)
			)
			(layer "F.SilkS")
		)
		(fp_line
			(start -0.67945 0.3048)
			(end -0.67945 -0.305054)
			(stroke
				(width 0.1)
				(type default)
			)
			(layer "F.Fab")
		)
		(fp_line
			(start -0.12065 0.3048)
			(end -0.67945 0.3048)
			(stroke
				(width 0.1)
				(type default)
			)
			(layer "F.Fab")
		)
		(fp_line
			(start 0.120396 0.3048)
			(end 0.120396 0.2794)
			(stroke
				(width 0.1)
				(type default)
			)
			(layer "F.Fab")
		)
		(fp_line
			(start 0.67945 0.3048)
			(end 0.120396 0.3048)
			(stroke
				(width 0.1)
				(type default)
			)
			(layer "F.Fab")
		)
		(fp_line
			(start -0.12065 0.2794)
			(end -0.12065 0.3048)
			(stroke
				(width 0.1)
				(type default)
			)
			(layer "F.Fab")
		)
		(fp_line
			(start 0.120396 0.2794)
			(end -0.12065 0.2794)
			(stroke
				(width 0.1)
				(type default)
			)
			(layer "F.Fab")
		)
		(fp_line
			(start -0.12065 -0.2794)
			(end 0.12065 -0.2794)
			(stroke
				(width 0.1)
				(type default)
			)
			(layer "F.Fab")
		)
		(fp_line
			(start 0.12065 -0.2794)
			(end 0.12065 -0.3048)
			(stroke
				(width 0.1)
				(type default)
			)
			(layer "F.Fab")
		)
		(fp_line
			(start 0.12065 -0.3048)
			(end 0.67945 -0.3048)
			(stroke
				(width 0.1)
				(type default)
			)
			(layer "F.Fab")
		)
		(fp_line
			(start 0.67945 -0.3048)
			(end 0.67945 0.3048)
			(stroke
				(width 0.1)
				(type default)
			)
			(layer "F.Fab")
		)
		(fp_line
			(start -0.67945 -0.305054)
			(end -0.12065 -0.305054)
			(stroke
				(width 0.1)
				(type default)
			)
			(layer "F.Fab")
		)
		(fp_line
			(start -0.12065 -0.305054)
			(end -0.12065 -0.2794)
			(stroke
				(width 0.1)
				(type default)
			)
			(layer "F.Fab")
		)
		(pad "1" smd circle
			(at -0.40005 0 270)
			(size 0 0)
			(layers "F.Cu" "F.Mask" "F.Paste")
			(net "P3V3_SSD6")
		)
		(pad "2" smd circle
			(at 0.40005 0 270)
			(size 0 0)
			(layers "F.Cu" "F.Mask" "F.Paste")
			(net "DUALPORT_N_SSD6")
		)
	)
	(footprint ""
		(layer "F.Cu")
		(at 235.056172 -172.55998 -90)
		(property "Reference" "R4258"
			(at 0 0 270)
			(layer "F.SilkS")
			(hide yes)
			(effects
				(font
					(size 1.27 1.27)
				)
			)
		)
		(property "Value" ""
			(at 0 0 270)
			(layer "F.Fab")
			(effects
				(font
					(size 1.27 1.27)
				)
			)
		)
		(duplicate_pad_numbers_are_jumpers no)
		(fp_line
			(start -0.7874 0.4064)
			(end -0.7874 -0.4064)
			(stroke
				(width 0.1524)
				(type default)
			)
			(layer "F.SilkS")
		)
		(fp_line
			(start 0.7874 0.4064)
			(end -0.7874 0.4064)
			(stroke
				(width 0.1524)
				(type default)
			)
			(layer "F.SilkS")
		)
		(fp_line
			(start -0.7874 -0.4064)
			(end 0.7874 -0.4064)
			(stroke
				(width 0.1524)
				(type default)
			)
			(layer "F.SilkS")
		)
		(fp_line
			(start 0.7874 -0.4064)
			(end 0.7874 0.4064)
			(stroke
				(width 0.1524)
				(type default)
			)
			(layer "F.SilkS")
		)
		(fp_line
			(start -0.67945 0.3048)
			(end -0.67945 -0.305054)
			(stroke
				(width 0.1)
				(type default)
			)
			(layer "F.Fab")
		)
		(fp_line
			(start -0.12065 0.3048)
			(end -0.67945 0.3048)
			(stroke
				(width 0.1)
				(type default)
			)
			(layer "F.Fab")
		)
		(fp_line
			(start 0.120396 0.3048)
			(end 0.120396 0.2794)
			(stroke
				(width 0.1)
				(type default)
			)
			(layer "F.Fab")
		)
		(fp_line
			(start 0.67945 0.3048)
			(end 0.120396 0.3048)
			(stroke
				(width 0.1)
				(type default)
			)
			(layer "F.Fab")
		)
		(fp_line
			(start -0.12065 0.2794)
			(end -0.12065 0.3048)
			(stroke
				(width 0.1)
				(type default)
			)
			(layer "F.Fab")
		)
		(fp_line
			(start 0.120396 0.2794)
			(end -0.12065 0.2794)
			(stroke
				(width 0.1)
				(type default)
			)
			(layer "F.Fab")
		)
		(fp_line
			(start -0.12065 -0.2794)
			(end 0.12065 -0.2794)
			(stroke
				(width 0.1)
				(type default)
			)
			(layer "F.Fab")
		)
		(fp_line
			(start 0.12065 -0.2794)
			(end 0.12065 -0.3048)
			(stroke
				(width 0.1)
				(type default)
			)
			(layer "F.Fab")
		)
		(fp_line
			(start 0.12065 -0.3048)
			(end 0.67945 -0.3048)
			(stroke
				(width 0.1)
				(type default)
			)
			(layer "F.Fab")
		)
		(fp_line
			(start 0.67945 -0.3048)
			(end 0.67945 0.3048)
			(stroke
				(width 0.1)
				(type default)
			)
			(layer "F.Fab")
		)
		(fp_line
			(start -0.67945 -0.305054)
			(end -0.12065 -0.305054)
			(stroke
				(width 0.1)
				(type default)
			)
			(layer "F.Fab")
		)
		(fp_line
			(start -0.12065 -0.305054)
			(end -0.12065 -0.2794)
			(stroke
				(width 0.1)
				(type default)
			)
			(layer "F.Fab")
		)
		(pad "1" smd circle
			(at -0.40005 0 270)
			(size 0 0)
			(layers "F.Cu" "F.Mask" "F.Paste")
			(net "RST_BIC_SRST_N")
		)
		(pad "2" smd circle
			(at 0.40005 0 270)
			(size 0 0)
			(layers "F.Cu" "F.Mask" "F.Paste")
			(net "GND")
		)
	)
	(footprint ""
		(layer "F.Cu")
		(at 189.39002 -72.766682 90)
		(property "Reference" "PR7071"
			(at 0 0 90)
			(layer "F.SilkS")
			(hide yes)
			(effects
				(font
					(size 1.27 1.27)
				)
			)
		)
		(property "Value" ""
			(at 0 0 90)
			(layer "F.Fab")
			(effects
				(font
					(size 1.27 1.27)
				)
			)
		)
		(duplicate_pad_numbers_are_jumpers no)
		(fp_line
			(start 0.7874 -0.4064)
			(end 0.7874 0.4064)
			(stroke
				(width 0.1524)
				(type default)
			)
			(layer "F.SilkS")
		)
		(fp_line
			(start -0.7874 -0.4064)
			(end 0.7874 -0.4064)
			(stroke
				(width 0.1524)
				(type default)
			)
			(layer "F.SilkS")
		)
		(fp_line
			(start 0.7874 0.4064)
			(end -0.7874 0.4064)
			(stroke
				(width 0.1524)
				(type default)
			)
			(layer "F.SilkS")
		)
		(fp_line
			(start -0.7874 0.4064)
			(end -0.7874 -0.4064)
			(stroke
				(width 0.1524)
				(type default)
			)
			(layer "F.SilkS")
		)
		(fp_line
			(start -0.12065 -0.305054)
			(end -0.12065 -0.2794)
			(stroke
				(width 0.1)
				(type default)
			)
			(layer "F.Fab")
		)
		(fp_line
			(start -0.67945 -0.305054)
			(end -0.12065 -0.305054)
			(stroke
				(width 0.1)
				(type default)
			)
			(layer "F.Fab")
		)
		(fp_line
			(start 0.67945 -0.3048)
			(end 0.67945 0.3048)
			(stroke
				(width 0.1)
				(type default)
			)
			(layer "F.Fab")
		)
		(fp_line
			(start 0.12065 -0.3048)
			(end 0.67945 -0.3048)
			(stroke
				(width 0.1)
				(type default)
			)
			(layer "F.Fab")
		)
		(fp_line
			(start 0.12065 -0.2794)
			(end 0.12065 -0.3048)
			(stroke
				(width 0.1)
				(type default)
			)
			(layer "F.Fab")
		)
		(fp_line
			(start -0.12065 -0.2794)
			(end 0.12065 -0.2794)
			(stroke
				(width 0.1)
				(type default)
			)
			(layer "F.Fab")
		)
		(fp_line
			(start 0.120396 0.2794)
			(end -0.12065 0.2794)
			(stroke
				(width 0.1)
				(type default)
			)
			(layer "F.Fab")
		)
		(fp_line
			(start -0.12065 0.2794)
			(end -0.12065 0.3048)
			(stroke
				(width 0.1)
				(type default)
			)
			(layer "F.Fab")
		)
		(fp_line
			(start 0.67945 0.3048)
			(end 0.120396 0.3048)
			(stroke
				(width 0.1)
				(type default)
			)
			(layer "F.Fab")
		)
		(fp_line
			(start 0.120396 0.3048)
			(end 0.120396 0.2794)
			(stroke
				(width 0.1)
				(type default)
			)
			(layer "F.Fab")
		)
		(fp_line
			(start -0.12065 0.3048)
			(end -0.67945 0.3048)
			(stroke
				(width 0.1)
				(type default)
			)
			(layer "F.Fab")
		)
		(fp_line
			(start -0.67945 0.3048)
			(end -0.67945 -0.305054)
			(stroke
				(width 0.1)
				(type default)
			)
			(layer "F.Fab")
		)
		(pad "1" smd circle
			(at -0.40005 0 90)
			(size 0 0)
			(layers "F.Cu" "F.Mask" "F.Paste")
			(net "P12V_SSD6_CO_ILIMIT")
		)
		(pad "2" smd circle
			(at 0.40005 0 90)
			(size 0 0)
			(layers "F.Cu" "F.Mask" "F.Paste")
			(net "GND")
		)
	)
	(footprint ""
		(layer "F.Cu")
		(at 151.2951 -59.577986 90)
		(property "Reference" "PC519"
			(at 0 0 90)
			(layer "F.SilkS")
			(hide yes)
			(effects
				(font
					(size 1.27 1.27)
				)
			)
		)
		(property "Value" ""
			(at 0 0 90)
			(layer "F.Fab")
			(effects
				(font
					(size 1.27 1.27)
				)
			)
		)
		(duplicate_pad_numbers_are_jumpers no)
		(fp_line
			(start 0.7874 -0.4064)
			(end 0.7874 0.4064)
			(stroke
				(width 0.1524)
				(type default)
			)
			(layer "F.SilkS")
		)
		(fp_line
			(start -0.7874 -0.4064)
			(end 0.7874 -0.4064)
			(stroke
				(width 0.1524)
				(type default)
			)
			(layer "F.SilkS")
		)
		(fp_line
			(start 0.7874 0.4064)
			(end -0.7874 0.4064)
			(stroke
				(width 0.1524)
				(type default)
			)
			(layer "F.SilkS")
		)
		(fp_line
			(start -0.7874 0.4064)
			(end -0.7874 -0.4064)
			(stroke
				(width 0.1524)
				(type default)
			)
			(layer "F.SilkS")
		)
		(fp_line
			(start -0.12065 -0.305054)
			(end -0.12065 -0.2794)
			(stroke
				(width 0.1)
				(type default)
			)
			(layer "F.Fab")
		)
		(fp_line
			(start -0.67945 -0.305054)
			(end -0.12065 -0.305054)
			(stroke
				(width 0.1)
				(type default)
			)
			(layer "F.Fab")
		)
		(fp_line
			(start 0.67945 -0.3048)
			(end 0.67945 0.3048)
			(stroke
				(width 0.1)
				(type default)
			)
			(layer "F.Fab")
		)
		(fp_line
			(start 0.12065 -0.3048)
			(end 0.67945 -0.3048)
			(stroke
				(width 0.1)
				(type default)
			)
			(layer "F.Fab")
		)
		(fp_line
			(start 0.12065 -0.2794)
			(end 0.12065 -0.3048)
			(stroke
				(width 0.1)
				(type default)
			)
			(layer "F.Fab")
		)
		(fp_line
			(start -0.12065 -0.2794)
			(end 0.12065 -0.2794)
			(stroke
				(width 0.1)
				(type default)
			)
			(layer "F.Fab")
		)
		(fp_line
			(start 0.120396 0.2794)
			(end -0.12065 0.2794)
			(stroke
				(width 0.1)
				(type default)
			)
			(layer "F.Fab")
		)
		(fp_line
			(start -0.12065 0.2794)
			(end -0.12065 0.3048)
			(stroke
				(width 0.1)
				(type default)
			)
			(layer "F.Fab")
		)
		(fp_line
			(start 0.67945 0.3048)
			(end 0.120396 0.3048)
			(stroke
				(width 0.1)
				(type default)
			)
			(layer "F.Fab")
		)
		(fp_line
			(start 0.120396 0.3048)
			(end 0.120396 0.2794)
			(stroke
				(width 0.1)
				(type default)
			)
			(layer "F.Fab")
		)
		(fp_line
			(start -0.12065 0.3048)
			(end -0.67945 0.3048)
			(stroke
				(width 0.1)
				(type default)
			)
			(layer "F.Fab")
		)
		(fp_line
			(start -0.67945 0.3048)
			(end -0.67945 -0.305054)
			(stroke
				(width 0.1)
				(type default)
			)
			(layer "F.Fab")
		)
		(pad "1" smd circle
			(at -0.40005 0 90)
			(size 0 0)
			(layers "F.Cu" "F.Mask" "F.Paste")
			(net "P3V3_SSD5_SS")
		)
		(pad "2" smd circle
			(at 0.40005 0 90)
			(size 0 0)
			(layers "F.Cu" "F.Mask" "F.Paste")
			(net "GND")
		)
	)
	(footprint ""
		(layer "F.Cu")
		(at 364.724188 -247.92305)
		(property "Reference" "J57"
			(at -1.4224 -4.562348 0)
			(unlocked yes)
			(layer "F.SilkS")
			(effects
				(font
					(size 0.7874 0.5842)
					(thickness 0.1524)
				)
				(justify left)
			)
		)
		(property "Value" ""
			(at 0 0 0)
			(layer "F.Fab")
			(effects
				(font
					(size 1.27 1.27)
				)
			)
		)
		(duplicate_pad_numbers_are_jumpers no)
		(fp_line
			(start -1.27 -3.81)
			(end 1.27 -3.81)
			(stroke
				(width 0.1524)
				(type default)
			)
			(layer "F.SilkS")
		)
		(fp_line
			(start -1.27 -0.7747)
			(end -1.27 -3.81)
			(stroke
				(width 0.1524)
				(type default)
			)
			(layer "F.SilkS")
		)
		(fp_line
			(start -1.27 3.81)
			(end -1.27 0.7747)
			(stroke
				(width 0.1524)
				(type default)
			)
			(layer "F.SilkS")
		)
		(fp_line
			(start 1.27 -3.81)
			(end 1.27 -3.3147)
			(stroke
				(width 0.1524)
				(type default)
			)
			(layer "F.SilkS")
		)
		(fp_line
			(start 1.27 -1.7653)
			(end 1.27 1.7653)
			(stroke
				(width 0.1524)
				(type default)
			)
			(layer "F.SilkS")
		)
		(fp_line
			(start 1.27 3.3147)
			(end 1.27 3.81)
			(stroke
				(width 0.1524)
				(type default)
			)
			(layer "F.SilkS")
		)
		(fp_line
			(start 1.27 3.81)
			(end -1.27 3.81)
			(stroke
				(width 0.1524)
				(type default)
			)
			(layer "F.SilkS")
		)
		(fp_poly
			(pts
				(xy 4.3942 -3.048) (xy 4.3942 -2.032) (xy 3.3782 -2.54)
			)
			(stroke
				(width 0)
				(type default)
			)
			(fill yes)
			(layer "F.SilkS")
		)
		(fp_line
			(start -1.27 -3.81)
			(end -1.27 3.81)
			(stroke
				(width 0.1)
				(type default)
			)
			(layer "F.Fab")
		)
		(fp_line
			(start -1.27 3.81)
			(end 1.27 3.81)
			(stroke
				(width 0.1)
				(type default)
			)
			(layer "F.Fab")
		)
		(fp_line
			(start 1.27 -3.81)
			(end -1.27 -3.81)
			(stroke
				(width 0.1)
				(type default)
			)
			(layer "F.Fab")
		)
		(fp_line
			(start 1.27 3.81)
			(end 1.27 -3.81)
			(stroke
				(width 0.1)
				(type default)
			)
			(layer "F.Fab")
		)
		(fp_poly
			(pts
				(xy 4.3942 -3.048) (xy 4.3942 -2.032) (xy 3.3782 -2.54)
			)
			(stroke
				(width 0)
				(type default)
			)
			(fill yes)
			(layer "F.Fab")
		)
		(fp_text user "3"
			(at 3.921252 2.54 90)
			(unlocked yes)
			(layer "F.SilkS")
			(effects
				(font
					(size 0.7874 0.5842)
					(thickness 0.1524)
				)
			)
		)
		(fp_text user "3"
			(at 3.921252 2.54 90)
			(unlocked yes)
			(layer "F.Fab")
			(effects
				(font
					(size 0.7874 0.5842)
					(thickness 0.1524)
				)
			)
		)
		(pad "1" smd rect
			(at 1.459992 -2.54 90)
			(size 1.27 3.429)
			(layers "F.Cu" "F.Mask" "F.Paste")
			(net "P3V3_AUX")
		)
		(pad "2" smd rect
			(at -1.459992 0 90)
			(size 1.27 3.429)
			(layers "F.Cu" "F.Mask" "F.Paste")
			(net "P3V3_LED")
		)
		(pad "3" smd rect
			(at 1.459992 2.54 90)
			(size 1.27 3.429)
			(layers "F.Cu" "F.Mask" "F.Paste")
			(net "Net_987")
		)
	)
	(footprint ""
		(layer "F.Cu")
		(at 429.156114 -32.848042 -90)
		(property "Reference" "R6115"
			(at 0 0 270)
			(layer "F.SilkS")
			(hide yes)
			(effects
				(font
					(size 1.27 1.27)
				)
			)
		)
		(property "Value" ""
			(at 0 0 270)
			(layer "F.Fab")
			(effects
				(font
					(size 1.27 1.27)
				)
			)
		)
		(duplicate_pad_numbers_are_jumpers no)
		(fp_line
			(start -0.7874 0.4064)
			(end -0.7874 -0.4064)
			(stroke
				(width 0.1524)
				(type default)
			)
			(layer "F.SilkS")
		)
		(fp_line
			(start 0.7874 0.4064)
			(end -0.7874 0.4064)
			(stroke
				(width 0.1524)
				(type default)
			)
			(layer "F.SilkS")
		)
		(fp_line
			(start -0.7874 -0.4064)
			(end 0.7874 -0.4064)
			(stroke
				(width 0.1524)
				(type default)
			)
			(layer "F.SilkS")
		)
		(fp_line
			(start 0.7874 -0.4064)
			(end 0.7874 0.4064)
			(stroke
				(width 0.1524)
				(type default)
			)
			(layer "F.SilkS")
		)
		(fp_line
			(start -0.67945 0.3048)
			(end -0.67945 -0.305054)
			(stroke
				(width 0.1)
				(type default)
			)
			(layer "F.Fab")
		)
		(fp_line
			(start -0.12065 0.3048)
			(end -0.67945 0.3048)
			(stroke
				(width 0.1)
				(type default)
			)
			(layer "F.Fab")
		)
		(fp_line
			(start 0.120396 0.3048)
			(end 0.120396 0.2794)
			(stroke
				(width 0.1)
				(type default)
			)
			(layer "F.Fab")
		)
		(fp_line
			(start 0.67945 0.3048)
			(end 0.120396 0.3048)
			(stroke
				(width 0.1)
				(type default)
			)
			(layer "F.Fab")
		)
		(fp_line
			(start -0.12065 0.2794)
			(end -0.12065 0.3048)
			(stroke
				(width 0.1)
				(type default)
			)
			(layer "F.Fab")
		)
		(fp_line
			(start 0.120396 0.2794)
			(end -0.12065 0.2794)
			(stroke
				(width 0.1)
				(type default)
			)
			(layer "F.Fab")
		)
		(fp_line
			(start -0.12065 -0.2794)
			(end 0.12065 -0.2794)
			(stroke
				(width 0.1)
				(type default)
			)
			(layer "F.Fab")
		)
		(fp_line
			(start 0.12065 -0.2794)
			(end 0.12065 -0.3048)
			(stroke
				(width 0.1)
				(type default)
			)
			(layer "F.Fab")
		)
		(fp_line
			(start 0.12065 -0.3048)
			(end 0.67945 -0.3048)
			(stroke
				(width 0.1)
				(type default)
			)
			(layer "F.Fab")
		)
		(fp_line
			(start 0.67945 -0.3048)
			(end 0.67945 0.3048)
			(stroke
				(width 0.1)
				(type default)
			)
			(layer "F.Fab")
		)
		(fp_line
			(start -0.67945 -0.305054)
			(end -0.12065 -0.305054)
			(stroke
				(width 0.1)
				(type default)
			)
			(layer "F.Fab")
		)
		(fp_line
			(start -0.12065 -0.305054)
			(end -0.12065 -0.2794)
			(stroke
				(width 0.1)
				(type default)
			)
			(layer "F.Fab")
		)
		(pad "1" smd circle
			(at -0.40005 0 270)
			(size 0 0)
			(layers "F.Cu" "F.Mask" "F.Paste")
			(net "SSD15_AUX_P3V3_EN_R")
		)
		(pad "2" smd circle
			(at 0.40005 0 270)
			(size 0 0)
			(layers "F.Cu" "F.Mask" "F.Paste")
			(net "P3V3_SSD15_CO_EN")
		)
	)
)
